(kicad_pcb
	(version 20241229)
	(generator "pcbnew")
	(generator_version "9.0")
	(general
		(thickness 1.711)
		(legacy_teardrops no)
	)
	(paper "A4")
	(title_block
		(title "Antmicro Baseboard for Jetson AGX Thor")
		(date "2026-02-18")
		(rev "1.1.0")
		(company "Antmicro Ltd")
		(comment 1 "www.antmicro.com")
		(comment 9 "footprints 557-561 of 1170")
	)
	(layers
		(0 "F.Cu" signal)
		(4 "In1.Cu" signal)
		(6 "In2.Cu" signal)
		(8 "In3.Cu" signal)
		(10 "In4.Cu" jumper)
		(12 "In5.Cu" signal)
		(14 "In6.Cu" signal)
		(16 "In7.Cu" signal)
		(18 "In8.Cu" signal)
		(2 "B.Cu" signal)
		(9 "F.Adhes" user "F.Adhesive")
		(11 "B.Adhes" user "B.Adhesive")
		(13 "F.Paste" user)
		(15 "B.Paste" user)
		(5 "F.SilkS" user "F.Silkscreen")
		(7 "B.SilkS" user "B.Silkscreen")
		(1 "F.Mask" user)
		(3 "B.Mask" user)
		(17 "Dwgs.User" user "User.Drawings")
		(19 "Cmts.User" user "User.Comments")
		(21 "Eco1.User" user "User.Eco1")
		(23 "Eco2.User" user "User.Eco2")
		(25 "Edge.Cuts" user)
		(27 "Margin" user)
		(31 "F.CrtYd" user "F.Courtyard")
		(29 "B.CrtYd" user "B.Courtyard")
		(35 "F.Fab" user)
		(33 "B.Fab" user)
	)
	(footprint "antmicro-footprints:C_0402_1005Metric"
		(layer "F.Cu")
		(at 153.5 107.5 180)
		(descr "Capacitor SMD 0402")
		(tags "capacitor SMD 0402")
		(property "Reference" "C216"
			(at -3.8 0.4 0)
			(layer "F.SilkS")
			(effects
				(font
					(size 0.7 0.7)
					(thickness 0.15)
				)
				(justify right top)
			)
		)
		(property "Value" "C_100n_0402"
			(at -1.022927 2.155213 0)
			(layer "F.Fab")
			(effects
				(font
					(size 0.7 0.7)
					(thickness 0.15)
				)
				(justify right top)
			)
		)
		(property "Datasheet" "https://www.murata.com/products/productdetail?partno=GRM155R61H104KE14%23"
			(at 0 0 0)
			(layer "F.Fab")
			(hide yes)
			(effects
				(font
					(size 1.27 1.27)
					(thickness 0.15)
				)
			)
		)
		(property "Description" "SMD Multilayer Ceramic Capacitor, 0.1 µF, 50 V, 0402 [1005 Metric], ± 10%, X5R, GRM Series"
			(at 0 0 0)
			(layer "F.Fab")
			(hide yes)
			(effects
				(font
					(size 1.27 1.27)
					(thickness 0.15)
				)
			)
		)
		(property "Manufacturer" "Murata"
			(at 0 0 180)
			(unlocked yes)
			(layer "F.Fab")
			(hide yes)
			(effects
				(font
					(size 1 1)
					(thickness 0.15)
				)
			)
		)
		(property "MPN" "GRM155R61H104KE14D"
			(at 0 0 180)
			(unlocked yes)
			(layer "F.Fab")
			(hide yes)
			(effects
				(font
					(size 1 1)
					(thickness 0.15)
				)
			)
		)
		(property "Val" "100n"
			(at 0 0 180)
			(unlocked yes)
			(layer "F.Fab")
			(hide yes)
			(effects
				(font
					(size 1 1)
					(thickness 0.15)
				)
			)
		)
		(property "License" "Apache-2.0"
			(at 0 0 180)
			(unlocked yes)
			(layer "F.Fab")
			(hide yes)
			(effects
				(font
					(size 1 1)
					(thickness 0.15)
				)
			)
		)
		(property "Author" "Antmicro"
			(at 0 0 180)
			(unlocked yes)
			(layer "F.Fab")
			(hide yes)
			(effects
				(font
					(size 1 1)
					(thickness 0.15)
				)
			)
		)
		(property "Voltage" "50V"
			(at 0 0 180)
			(unlocked yes)
			(layer "F.Fab")
			(hide yes)
			(effects
				(font
					(size 1 1)
					(thickness 0.15)
				)
			)
		)
		(property "Dielectric" "X5R"
			(at 0 0 180)
			(unlocked yes)
			(layer "F.Fab")
			(hide yes)
			(effects
				(font
					(size 1 1)
					(thickness 0.15)
				)
			)
		)
		(sheetname "/SoM_IO/")
		(sheetfile "som_io.kicad_sch")
		(attr smd)
		(fp_poly
			(pts
				(xy -0.925 -0.47) (xy 0.925 -0.47) (xy 0.925 0.47) (xy -0.925 0.47)
			)
			(stroke
				(width 0.05)
				(type default)
			)
			(fill no)
			(layer "F.CrtYd")
		)
		(fp_line
			(start 0.504 0.248)
			(end -0.494 0.248)
			(stroke
				(width 0.15)
				(type solid)
			)
			(layer "F.Fab")
		)
		(fp_line
			(start 0.504 -0.25)
			(end 0.504 0.248)
			(stroke
				(width 0.15)
				(type solid)
			)
			(layer "F.Fab")
		)
		(fp_line
			(start -0.494 0.248)
			(end -0.494 -0.25)
			(stroke
				(width 0.15)
				(type solid)
			)
			(layer "F.Fab")
		)
		(fp_line
			(start -0.494 -0.25)
			(end 0.504 -0.25)
			(stroke
				(width 0.15)
				(type solid)
			)
			(layer "F.Fab")
		)
		(fp_text user "License: Apache-2.0"
			(at -0.939 5.799 0)
			(layer "F.Fab")
			(effects
				(font
					(size 0.7 0.7)
					(thickness 0.15)
				)
				(justify right top)
			)
		)
		(fp_text user "Author: Antmicro"
			(at -0.939 3.399 0)
			(layer "F.Fab")
			(effects
				(font
					(size 0.7 0.7)
					(thickness 0.15)
				)
				(justify right top)
			)
		)
		(fp_text user "${REFERENCE}"
			(at -0.939 4.599 0)
			(layer "F.Fab")
			(effects
				(font
					(size 0.7 0.7)
					(thickness 0.15)
				)
				(justify right top)
			)
		)
		(pad "1" smd roundrect
			(at -0.48 0 180)
			(size 0.59 0.64)
			(layers "F.Cu" "F.Mask" "F.Paste")
			(roundrect_rratio 0.25)
			(net 1 "GND")
			(pintype "passive")
		)
		(pad "2" smd roundrect
			(at 0.48 0 180)
			(size 0.59 0.64)
			(layers "F.Cu" "F.Mask" "F.Paste")
			(roundrect_rratio 0.25)
			(net 11 "+1V8")
			(pintype "passive")
		)
	)
	(footprint "antmicro-footprints:R_0402_1005Metric"
		(layer "F.Cu")
		(at 145.424391 125.91 90)
		(descr "Resistor SMD 0402")
		(tags "resistor SMD 0402")
		(property "Reference" "R317"
			(at 1.71 0.408 90)
			(layer "F.SilkS")
			(effects
				(font
					(size 0.7 0.7)
					(thickness 0.15)
				)
				(justify left bottom)
			)
		)
		(property "Value" "R_30k_0402"
			(at -1.011843 1.772047 90)
			(layer "F.Fab")
			(effects
				(font
					(size 0.7 0.7)
					(thickness 0.15)
				)
				(justify left bottom)
			)
		)
		(property "Datasheet" "https://www.bourns.com/docs/product-datasheets/cr.pdf"
			(at 0 0 90)
			(layer "F.Fab")
			(hide yes)
			(effects
				(font
					(size 1.27 1.27)
					(thickness 0.15)
				)
			)
		)
		(property "Description" "SMD Chip Resistor, 30 kohm, ± 1%, 63 mW, 0402 [1005 Metric], Thick Film, General Purpose"
			(at 0 0 90)
			(layer "F.Fab")
			(hide yes)
			(effects
				(font
					(size 1.27 1.27)
					(thickness 0.15)
				)
			)
		)
		(property "MPN" "CR0402-FX-3002GLF"
			(at 0 0 90)
			(unlocked yes)
			(layer "F.Fab")
			(hide yes)
			(effects
				(font
					(size 1 1)
					(thickness 0.15)
				)
			)
		)
		(property "Manufacturer" "Bourns"
			(at 0 0 90)
			(unlocked yes)
			(layer "F.Fab")
			(hide yes)
			(effects
				(font
					(size 1 1)
					(thickness 0.15)
				)
			)
		)
		(property "License" "Apache-2.0"
			(at 0 0 90)
			(unlocked yes)
			(layer "F.Fab")
			(hide yes)
			(effects
				(font
					(size 1 1)
					(thickness 0.15)
				)
			)
		)
		(property "Author" "Antmicro"
			(at 0 0 90)
			(unlocked yes)
			(layer "F.Fab")
			(hide yes)
			(effects
				(font
					(size 1 1)
					(thickness 0.15)
				)
			)
		)
		(property "Val" "30k"
			(at 0 0 90)
			(unlocked yes)
			(layer "F.Fab")
			(hide yes)
			(effects
				(font
					(size 1 1)
					(thickness 0.15)
				)
			)
		)
		(property "Tolerance" "1%"
			(at 0 0 90)
			(unlocked yes)
			(layer "F.Fab")
			(hide yes)
			(effects
				(font
					(size 1 1)
					(thickness 0.15)
				)
			)
		)
		(component_classes
			(class "DCDC_1V8")
		)
		(sheetname "/DCDC/")
		(sheetfile "dcdc.kicad_sch")
		(attr smd)
		(fp_rect
			(start -0.925 -0.47)
			(end 0.925 0.47)
			(stroke
				(width 0.05)
				(type default)
			)
			(fill no)
			(layer "F.CrtYd")
		)
		(fp_rect
			(start -0.5 -0.25)
			(end 0.5 0.25)
			(stroke
				(width 0.15)
				(type solid)
			)
			(fill no)
			(layer "F.Fab")
		)
		(fp_text user "License: Apache-2.0"
			(at -0.95 5.169 90)
			(layer "F.Fab")
			(effects
				(font
					(size 0.7 0.7)
					(thickness 0.15)
				)
				(justify left bottom)
			)
		)
		(fp_text user "Author: Antmicro"
			(at -0.95 4.169 90)
			(layer "F.Fab")
			(effects
				(font
					(size 0.7 0.7)
					(thickness 0.15)
				)
				(justify left bottom)
			)
		)
		(fp_text user "${REFERENCE}"
			(at -0.95 3.168 90)
			(layer "F.Fab")
			(effects
				(font
					(size 0.7 0.7)
					(thickness 0.15)
				)
				(justify left bottom)
			)
		)
		(pad "1" smd roundrect
			(at -0.48 0 90)
			(size 0.59 0.64)
			(layers "F.Cu" "F.Mask" "F.Paste")
			(roundrect_rratio 0.25)
			(net 1222 "/DCDC/1V8_FB")
			(pintype "passive")
		)
		(pad "2" smd roundrect
			(at 0.48 0 90)
			(size 0.59 0.64)
			(layers "F.Cu" "F.Mask" "F.Paste")
			(roundrect_rratio 0.25)
			(net 17 "/DCDC/1V8_OUT")
			(pintype "passive")
		)
	)
	(footprint "antmicro-footprints:R_0402_1005Metric"
		(layer "F.Cu")
		(at 156.6 119.4 180)
		(descr "Resistor SMD 0402")
		(tags "resistor SMD 0402")
		(property "Reference" "R358"
			(at -3.6 0.4 0)
			(layer "F.SilkS")
			(effects
				(font
					(size 0.7 0.7)
					(thickness 0.15)
				)
				(justify right top)
			)
		)
		(property "Value" "R_2k2_0402"
			(at -1.011843 1.772047 0)
			(layer "F.Fab")
			(effects
				(font
					(size 0.7 0.7)
					(thickness 0.15)
				)
				(justify right top)
			)
		)
		(property "Datasheet" "https://www.bourns.com/docs/product-datasheets/cr.pdf"
			(at 0 0 0)
			(layer "F.Fab")
			(hide yes)
			(effects
				(font
					(size 1.27 1.27)
					(thickness 0.15)
				)
			)
		)
		(property "Description" "SMD Chip Resistor, 2.2 kohm, ± 1%, 62.5 mW, 0402 [1005 Metric], Thick Film, General Purpose"
			(at 0 0 0)
			(layer "F.Fab")
			(hide yes)
			(effects
				(font
					(size 1.27 1.27)
					(thickness 0.15)
				)
			)
		)
		(property "MPN" "CR0402-FX-2201GLF"
			(at 0 0 180)
			(unlocked yes)
			(layer "F.Fab")
			(hide yes)
			(effects
				(font
					(size 1 1)
					(thickness 0.15)
				)
			)
		)
		(property "Manufacturer" "Bourns"
			(at 0 0 180)
			(unlocked yes)
			(layer "F.Fab")
			(hide yes)
			(effects
				(font
					(size 1 1)
					(thickness 0.15)
				)
			)
		)
		(property "License" "Apache-2.0"
			(at 0 0 180)
			(unlocked yes)
			(layer "F.Fab")
			(hide yes)
			(effects
				(font
					(size 1 1)
					(thickness 0.15)
				)
			)
		)
		(property "Author" "Antmicro"
			(at 0 0 180)
			(unlocked yes)
			(layer "F.Fab")
			(hide yes)
			(effects
				(font
					(size 1 1)
					(thickness 0.15)
				)
			)
		)
		(property "Val" "2k2"
			(at 0 0 180)
			(unlocked yes)
			(layer "F.Fab")
			(hide yes)
			(effects
				(font
					(size 1 1)
					(thickness 0.15)
				)
			)
		)
		(property "Tolerance" "1%"
			(at 0 0 180)
			(unlocked yes)
			(layer "F.Fab")
			(hide yes)
			(effects
				(font
					(size 1 1)
					(thickness 0.15)
				)
			)
		)
		(sheetname "/SoM_IO/")
		(sheetfile "som_io.kicad_sch")
		(attr smd exclude_from_pos_files exclude_from_bom dnp)
		(fp_rect
			(start -0.925 -0.47)
			(end 0.925 0.47)
			(stroke
				(width 0.05)
				(type default)
			)
			(fill no)
			(layer "F.CrtYd")
		)
		(fp_rect
			(start -0.5 -0.25)
			(end 0.5 0.25)
			(stroke
				(width 0.15)
				(type solid)
			)
			(fill no)
			(layer "F.Fab")
		)
		(fp_text user "License: Apache-2.0"
			(at -0.95 5.169 0)
			(layer "F.Fab")
			(effects
				(font
					(size 0.7 0.7)
					(thickness 0.15)
				)
				(justify right top)
			)
		)
		(fp_text user "${REFERENCE}"
			(at -0.95 3.168 0)
			(layer "F.Fab")
			(effects
				(font
					(size 0.7 0.7)
					(thickness 0.15)
				)
				(justify right top)
			)
		)
		(fp_text user "Author: Antmicro"
			(at -0.95 4.169 0)
			(layer "F.Fab")
			(effects
				(font
					(size 0.7 0.7)
					(thickness 0.15)
				)
				(justify right top)
			)
		)
		(pad "1" smd roundrect
			(at -0.48 0 180)
			(size 0.59 0.64)
			(layers "F.Cu" "F.Mask" "F.Paste")
			(roundrect_rratio 0.25)
			(net 11 "+1V8")
			(pintype "passive")
		)
		(pad "2" smd roundrect
			(at 0.48 0 180)
			(size 0.59 0.64)
			(layers "F.Cu" "F.Mask" "F.Paste")
			(roundrect_rratio 0.25)
			(net 145 "/SoM_IO/I2C3_SDA_1V8")
			(pintype "passive")
		)
	)
	(footprint "antmicro-footprints:R_0402_1005Metric"
		(layer "F.Cu")
		(at 181.75 107.15 -90)
		(descr "Resistor SMD 0402")
		(tags "resistor SMD 0402")
		(property "Reference" "R42"
			(at -3.17 0.44 90)
			(layer "F.SilkS")
			(effects
				(font
					(size 0.7 0.7)
					(thickness 0.15)
				)
				(justify right top)
			)
		)
		(property "Value" "R_200k_0402"
			(at -1.011843 1.772047 90)
			(layer "F.Fab")
			(effects
				(font
					(size 0.7 0.7)
					(thickness 0.15)
				)
				(justify right top)
			)
		)
		(property "Datasheet" "https://www.bourns.com/docs/product-datasheets/cr.pdf"
			(at 0 0 90)
			(layer "F.Fab")
			(hide yes)
			(effects
				(font
					(size 1.27 1.27)
					(thickness 0.15)
				)
			)
		)
		(property "Description" "SMD Chip Resistor, 200 kohm, ± 1%, 62.5 mW, 0402 [1005 Metric], Thick Film, General Purpose"
			(at 0 0 90)
			(layer "F.Fab")
			(hide yes)
			(effects
				(font
					(size 1.27 1.27)
					(thickness 0.15)
				)
			)
		)
		(property "MPN" "CR0402-FX-2003GLF"
			(at 0 0 270)
			(unlocked yes)
			(layer "F.Fab")
			(hide yes)
			(effects
				(font
					(size 1 1)
					(thickness 0.15)
				)
			)
		)
		(property "Manufacturer" "Bourns"
			(at 0 0 270)
			(unlocked yes)
			(layer "F.Fab")
			(hide yes)
			(effects
				(font
					(size 1 1)
					(thickness 0.15)
				)
			)
		)
		(property "License" "Apache-2.0"
			(at 0 0 270)
			(unlocked yes)
			(layer "F.Fab")
			(hide yes)
			(effects
				(font
					(size 1 1)
					(thickness 0.15)
				)
			)
		)
		(property "Author" "Antmicro"
			(at 0 0 270)
			(unlocked yes)
			(layer "F.Fab")
			(hide yes)
			(effects
				(font
					(size 1 1)
					(thickness 0.15)
				)
			)
		)
		(property "Val" "200k"
			(at 0 0 270)
			(unlocked yes)
			(layer "F.Fab")
			(hide yes)
			(effects
				(font
					(size 1 1)
					(thickness 0.15)
				)
			)
		)
		(property "Tolerance" "1%"
			(at 0 0 270)
			(unlocked yes)
			(layer "F.Fab")
			(hide yes)
			(effects
				(font
					(size 1 1)
					(thickness 0.15)
				)
			)
		)
		(sheetname "/DCDC/")
		(sheetfile "dcdc.kicad_sch")
		(attr smd)
		(fp_rect
			(start -0.925 -0.47)
			(end 0.925 0.47)
			(stroke
				(width 0.05)
				(type default)
			)
			(fill no)
			(layer "F.CrtYd")
		)
		(fp_rect
			(start -0.5 -0.25)
			(end 0.5 0.25)
			(stroke
				(width 0.15)
				(type solid)
			)
			(fill no)
			(layer "F.Fab")
		)
		(fp_text user "${REFERENCE}"
			(at -0.95 3.168 90)
			(layer "F.Fab")
			(effects
				(font
					(size 0.7 0.7)
					(thickness 0.15)
				)
				(justify right top)
			)
		)
		(fp_text user "Author: Antmicro"
			(at -0.95 4.169 90)
			(layer "F.Fab")
			(effects
				(font
					(size 0.7 0.7)
					(thickness 0.15)
				)
				(justify right top)
			)
		)
		(fp_text user "License: Apache-2.0"
			(at -0.95 5.169 90)
			(layer "F.Fab")
			(effects
				(font
					(size 0.7 0.7)
					(thickness 0.15)
				)
				(justify right top)
			)
		)
		(pad "1" smd roundrect
			(at -0.48 0 270)
			(size 0.59 0.64)
			(layers "F.Cu" "F.Mask" "F.Paste")
			(roundrect_rratio 0.25)
			(net 1 "GND")
			(pintype "passive")
		)
		(pad "2" smd roundrect
			(at 0.48 0 270)
			(size 0.59 0.64)
			(layers "F.Cu" "F.Mask" "F.Paste")
			(roundrect_rratio 0.25)
			(net 1215 "/DCDC/5V_MODE2")
			(pintype "passive")
		)
	)
	(footprint "antmicro-footprints:R_0402_1005Metric"
		(layer "F.Cu")
		(at 162.694468 98.145 90)
		(descr "Resistor SMD 0402")
		(tags "resistor SMD 0402")
		(property "Reference" "R364"
			(at -0.955 -1.694468 90)
			(layer "F.SilkS")
			(effects
				(font
					(size 0.7 0.7)
					(thickness 0.15)
				)
				(justify left bottom)
			)
		)
		(property "Value" "R_27R_0402"
			(at -1.011843 1.772047 90)
			(layer "F.Fab")
			(effects
				(font
					(size 0.7 0.7)
					(thickness 0.15)
				)
				(justify left bottom)
			)
		)
		(property "Datasheet" "https://www.bourns.com/docs/product-datasheets/cr.pdf"
			(at 0 0 90)
			(layer "F.Fab")
			(hide yes)
			(effects
				(font
					(size 1.27 1.27)
					(thickness 0.15)
				)
			)
		)
		(property "Description" "SMD Chip Resistor, 27 ohm, ± 1%, 63 mW, 0402 [1005 Metric], Thick Film, General Purpose"
			(at 0 0 90)
			(layer "F.Fab")
			(hide yes)
			(effects
				(font
					(size 1.27 1.27)
					(thickness 0.15)
				)
			)
		)
		(property "Manufacturer" "Bourns"
			(at 0 0 90)
			(unlocked yes)
			(layer "F.Fab")
			(hide yes)
			(effects
				(font
					(size 1 1)
					(thickness 0.15)
				)
			)
		)
		(property "MPN" "CR0402-FX-27R0GLF"
			(at 0 0 90)
			(unlocked yes)
			(layer "F.Fab")
			(hide yes)
			(effects
				(font
					(size 1 1)
					(thickness 0.15)
				)
			)
		)
		(property "Val" "27R"
			(at 0 0 90)
			(unlocked yes)
			(layer "F.Fab")
			(hide yes)
			(effects
				(font
					(size 1 1)
					(thickness 0.15)
				)
			)
		)
		(property "License" "Apache-2.0"
			(at 0 0 90)
			(unlocked yes)
			(layer "F.Fab")
			(hide yes)
			(effects
				(font
					(size 1 1)
					(thickness 0.15)
				)
			)
		)
		(property "Author" "Antmicro"
			(at 0 0 90)
			(unlocked yes)
			(layer "F.Fab")
			(hide yes)
			(effects
				(font
					(size 1 1)
					(thickness 0.15)
				)
			)
		)
		(property "Tolerance" "1%"
			(at 0 0 90)
			(unlocked yes)
			(layer "F.Fab")
			(hide yes)
			(effects
				(font
					(size 1 1)
					(thickness 0.15)
				)
			)
		)
		(component_classes
			(class "DCDC_SOM")
		)
		(sheetname "/DCDC/")
		(sheetfile "dcdc.kicad_sch")
		(attr smd)
		(fp_rect
			(start -0.925 -0.47)
			(end 0.925 0.47)
			(stroke
				(width 0.05)
				(type default)
			)
			(fill no)
			(layer "F.CrtYd")
		)
		(fp_rect
			(start -0.5 -0.25)
			(end 0.5 0.25)
			(stroke
				(width 0.15)
				(type solid)
			)
			(fill no)
			(layer "F.Fab")
		)
		(fp_text user "${REFERENCE}"
			(at -0.95 3.168 90)
			(layer "F.Fab")
			(effects
				(font
					(size 0.7 0.7)
					(thickness 0.15)
				)
				(justify left bottom)
			)
		)
		(fp_text user "Author: Antmicro"
			(at -0.95 4.169 90)
			(layer "F.Fab")
			(effects
				(font
					(size 0.7 0.7)
					(thickness 0.15)
				)
				(justify left bottom)
			)
		)
		(fp_text user "License: Apache-2.0"
			(at -0.95 5.169 90)
			(layer "F.Fab")
			(effects
				(font
					(size 0.7 0.7)
					(thickness 0.15)
				)
				(justify left bottom)
			)
		)
		(pad "1" smd roundrect
			(at -0.48 0 90)
			(size 0.59 0.64)
			(layers "F.Cu" "F.Mask" "F.Paste")
			(roundrect_rratio 0.25)
			(net 1283 "Net-(U22-IN+)")
			(pintype "passive")
		)
		(pad "2" smd roundrect
			(at 0.48 0 90)
			(size 0.59 0.64)
			(layers "F.Cu" "F.Mask" "F.Paste")
			(roundrect_rratio 0.25)
			(net 903 "/DCDC/16V_OUT")
			(pintype "passive")
		)
	)
)
